(kicad_pcb
	(version 20260206)
	(generator "pcbnew")
	(generator_version "10.0")
	(general
		(thickness 1.6)
		(legacy_teardrops no)
	)
	(paper "A4")
	(title_block
		(title "Wiwynn_Tioga_Pass_MB.brd")
		(comment 1 "Tioga Pass / footprints 1341-1344 of 4770")
	)
	(layers
		(0 "F.Cu" signal "TOP")
		(4 "In1.Cu" signal "L2GND")
		(6 "In2.Cu" signal "L3")
		(8 "In3.Cu" signal "L4GND")
		(10 "In4.Cu" signal "L5")
		(12 "In5.Cu" signal "L6GND")
		(14 "In6.Cu" signal "L7VCC")
		(16 "In7.Cu" signal "L8VCC")
		(18 "In8.Cu" signal "L9GND")
		(20 "In9.Cu" signal "L10")
		(22 "In10.Cu" signal "L11GND")
		(24 "In11.Cu" signal "L12")
		(26 "In12.Cu" signal "L13GND")
		(2 "B.Cu" signal "BOTTOM")
		(9 "F.Adhes" user "F.Adhesive")
		(11 "B.Adhes" user "B.Adhesive")
		(13 "F.Paste" user "Package Geometry/Pastemask Top")
		(15 "B.Paste" user "Package Geometry/Pastemask Bottom")
		(5 "F.SilkS" user "Ref Des/Silkscreen Top")
		(7 "B.SilkS" user "Ref Des/Silkscreen Bottom")
		(1 "F.Mask" user "Board Geometry/Soldermask Top")
		(3 "B.Mask" user "Board Geometry/Soldermask Bottom")
		(17 "Dwgs.User" user "User.Drawings")
		(19 "Cmts.User" user "User.Comments")
		(21 "Eco1.User" user "User.Eco1")
		(23 "Eco2.User" user "User.Eco2")
		(25 "Edge.Cuts" user "Board Geometry/Outline")
		(27 "Margin" user)
		(31 "F.CrtYd" user "Package Geometry/Place Bound Top")
		(29 "B.CrtYd" user "Package Geometry/Place Bound Bottom")
		(35 "F.Fab" user "Ref Des/Assembly Top")
		(33 "B.Fab" user "Ref Des/Assembly Bottom")
	)
	(footprint ""
		(layer "F.Cu")
		(at 122.490484 12.014454 -90)
		(property "Reference" "T1P8"
			(at 0 0 270)
			(layer "F.SilkS")
			(hide yes)
			(effects
				(font
					(size 1.27 1.27)
				)
			)
		)
		(property "Value" "*"
			(at -3.302 1.12395 270)
			(unlocked yes)
			(layer "F.Fab")
			(hide yes)
			(effects
				(font
					(size 0.889 0.889)
					(thickness 0.1524)
				)
			)
		)
		(property "Device Type" "TPAD-DIFF-4P-GP_DISCRET-GB3-TPA"
			(at -3.302 -0.40005 270)
			(unlocked yes)
			(layer "F.Fab")
			(hide yes)
			(effects
				(font
					(size 0.889 0.889)
					(thickness 0.1524)
				)
			)
		)
		(duplicate_pad_numbers_are_jumpers no)
		(fp_line
			(start -2.286 2.286)
			(end 2.286 2.286)
			(stroke
				(width 0.1524)
				(type default)
			)
			(layer "F.SilkS")
		)
		(fp_line
			(start 2.286 2.286)
			(end 2.286 -2.286)
			(stroke
				(width 0.1524)
				(type default)
			)
			(layer "F.SilkS")
		)
		(fp_line
			(start -2.286 -2.286)
			(end -2.286 2.286)
			(stroke
				(width 0.1524)
				(type default)
			)
			(layer "F.SilkS")
		)
		(fp_line
			(start 2.286 -2.286)
			(end -2.286 -2.286)
			(stroke
				(width 0.1524)
				(type default)
			)
			(layer "F.SilkS")
		)
		(fp_line
			(start -2.413 -2.413)
			(end -2.413 -1.143)
			(stroke
				(width 0.4064)
				(type default)
			)
			(layer "F.SilkS")
		)
		(fp_line
			(start -1.143 -2.413)
			(end -2.413 -2.413)
			(stroke
				(width 0.4064)
				(type default)
			)
			(layer "F.SilkS")
		)
		(fp_rect
			(start -2.54 2.54)
			(end 2.54 -2.54)
			(stroke
				(width 0)
				(type default)
			)
			(fill no)
			(layer "F.CrtYd")
		)
		(fp_rect
			(start -2.54 2.54)
			(end 2.54 -2.54)
			(stroke
				(width 0)
				(type default)
			)
			(fill no)
			(layer "F.Fab")
		)
		(pad "1" thru_hole circle
			(at -1.27 -1.27 270)
			(size 1.524 1.524)
			(drill 0.9144)
			(layers "*.Cu" "*.Mask")
			(remove_unused_layers no)
			(net "L3_73OHM_6INCH_DP")
			(clearance -0.0508)
			(thermal_gap 0.127)
			(padstack
				(mode front_inner_back)
				(layer "Inner"
					(shape circle)
					(size 1.1684 1.1684)
					(clearance 0.127)
				)
				(layer "B.Cu"
					(shape circle)
					(size 1.524 1.524)
					(clearance -0.0508)
				)
			)
		)
		(pad "2" thru_hole circle
			(at 1.27 -1.27 270)
			(size 1.524 1.524)
			(drill 0.9144)
			(layers "*.Cu" "*.Mask")
			(remove_unused_layers no)
			(net "L3_73OHM_6INCH_DN")
			(clearance -0.0508)
			(thermal_gap 0.127)
			(padstack
				(mode front_inner_back)
				(layer "Inner"
					(shape circle)
					(size 1.1684 1.1684)
					(clearance 0.127)
				)
				(layer "B.Cu"
					(shape circle)
					(size 1.524 1.524)
					(clearance -0.0508)
				)
			)
		)
		(pad "GND1" thru_hole rect
			(at -1.27 1.27 270)
			(size 1.524 1.524)
			(drill 0.9144)
			(layers "*.Cu" "*.Mask")
			(remove_unused_layers no)
			(net "GND")
			(clearance -0.0508)
			(thermal_gap 0.127)
			(padstack
				(mode front_inner_back)
				(layer "Inner"
					(shape circle)
					(size 1.1684 1.1684)
					(clearance 0.127)
				)
				(layer "B.Cu"
					(shape rect)
					(size 1.524 1.524)
					(clearance -0.0508)
				)
			)
		)
		(pad "GND2" thru_hole rect
			(at 1.27 1.27 270)
			(size 1.524 1.524)
			(drill 0.9144)
			(layers "*.Cu" "*.Mask")
			(remove_unused_layers no)
			(net "GND")
			(clearance -0.0508)
			(thermal_gap 0.127)
			(padstack
				(mode front_inner_back)
				(layer "Inner"
					(shape circle)
					(size 1.1684 1.1684)
					(clearance 0.127)
				)
				(layer "B.Cu"
					(shape rect)
					(size 1.524 1.524)
					(clearance -0.0508)
				)
			)
		)
	)
	(footprint ""
		(layer "F.Cu")
		(at 13.8938 -23.241 90)
		(property "Reference" "C1F20"
			(at 0 0 90)
			(layer "F.SilkS")
			(hide yes)
			(effects
				(font
					(size 1.27 1.27)
				)
			)
		)
		(property "Value" ""
			(at 0 0 90)
			(layer "F.Fab")
			(effects
				(font
					(size 1.27 1.27)
				)
			)
		)
		(duplicate_pad_numbers_are_jumpers no)
		(fp_rect
			(start -0.3048 -0.1016)
			(end 0.3048 0.9906)
			(stroke
				(width 0)
				(type default)
			)
			(fill no)
			(layer "F.CrtYd")
		)
		(fp_line
			(start 0.3048 -0.1016)
			(end -0.3048 -0.1016)
			(stroke
				(width 0.1)
				(type default)
			)
			(layer "F.Fab")
		)
		(fp_line
			(start -0.3048 -0.1016)
			(end -0.3048 0.9906)
			(stroke
				(width 0.1)
				(type default)
			)
			(layer "F.Fab")
		)
		(fp_line
			(start 0.3048 0.9906)
			(end 0.3048 -0.1016)
			(stroke
				(width 0.1)
				(type default)
			)
			(layer "F.Fab")
		)
		(fp_line
			(start -0.3048 0.9906)
			(end 0.3048 0.9906)
			(stroke
				(width 0.1)
				(type default)
			)
			(layer "F.Fab")
		)
		(pad "1" smd rect
			(at 0 0 90)
			(size 0.508 0.508)
			(layers "F.Cu" "F.Mask" "F.Paste")
			(net "P3E_CPU1_PE3_MP_C_TXN<0>")
		)
		(pad "2" smd rect
			(at 0 0.889 90)
			(size 0.508 0.508)
			(layers "F.Cu" "F.Mask" "F.Paste")
			(net "P3E_CPU1_PE3_MP_TXN<0>")
		)
		(zone
			(layer "F.Cu")
			(hatch none 0.5)
			(connect_pads
				(clearance 0)
			)
			(min_thickness 0.25)
			(keepout
				(tracks allowed)
				(vias not_allowed)
				(pads allowed)
				(copperpour not_allowed)
				(footprints allowed)
			)
			(placement
				(enabled no)
				(sheetname "")
			)
			(fill
				(thermal_gap 0.5)
				(thermal_bridge_width 0.5)
				(island_removal_mode 0)
			)
			(polygon
				(pts
					(xy 14.1478 -22.987) (xy 14.5288 -22.987) (xy 14.5288 -23.495) (xy 14.1478 -23.495)
				)
			)
		)
		(zone
			(layer "F.Cu")
			(hatch none 0.5)
			(connect_pads
				(clearance 0)
			)
			(min_thickness 0.25)
			(keepout
				(tracks not_allowed)
				(vias allowed)
				(pads allowed)
				(copperpour not_allowed)
				(footprints allowed)
			)
			(placement
				(enabled no)
				(sheetname "")
			)
			(fill
				(thermal_gap 0.5)
				(thermal_bridge_width 0.5)
				(island_removal_mode 0)
			)
			(polygon
				(pts
					(xy 14.1478 -22.987) (xy 14.5288 -22.987) (xy 14.5288 -23.495) (xy 14.1478 -23.495)
				)
			)
		)
	)
	(footprint ""
		(layer "F.Cu")
		(at 366.268 3.81 90)
		(property "Reference" "J7G3"
			(at 5.63245 2.22758 0)
			(unlocked yes)
			(layer "F.SilkS")
			(effects
				(font
					(size 0.7874 0.5842)
					(thickness 0.1524)
				)
			)
		)
		(property "Value" ""
			(at 0 0 90)
			(layer "F.Fab")
			(effects
				(font
					(size 1.27 1.27)
				)
			)
		)
		(duplicate_pad_numbers_are_jumpers no)
		(fp_line
			(start 3.8227 -1.27)
			(end 3.8227 13.97)
			(stroke
				(width 0.1524)
				(type default)
			)
			(layer "F.SilkS")
		)
		(fp_line
			(start -1.2827 -1.27)
			(end 3.8227 -1.27)
			(stroke
				(width 0.1524)
				(type default)
			)
			(layer "F.SilkS")
		)
		(fp_line
			(start 3.7592 -1.143)
			(end 3.758184 -1.143)
			(stroke
				(width 0.1)
				(type default)
			)
			(layer "F.SilkS")
		)
		(fp_line
			(start -1.2192 -1.143)
			(end -1.218946 -1.143)
			(stroke
				(width 0.1)
				(type default)
			)
			(layer "F.SilkS")
		)
		(fp_line
			(start 3.7592 13.843)
			(end 3.758946 13.843)
			(stroke
				(width 0.1524)
				(type default)
			)
			(layer "F.SilkS")
		)
		(fp_line
			(start -1.2192 13.843)
			(end -1.218946 13.843)
			(stroke
				(width 0.1524)
				(type default)
			)
			(layer "F.SilkS")
		)
		(fp_line
			(start 3.8227 13.97)
			(end -1.2827 13.97)
			(stroke
				(width 0.1524)
				(type default)
			)
			(layer "F.SilkS")
		)
		(fp_line
			(start -1.2827 13.97)
			(end -1.2827 -1.27)
			(stroke
				(width 0.1524)
				(type default)
			)
			(layer "F.SilkS")
		)
		(fp_poly
			(pts
				(xy -1.7145 -0.005588) (xy -2.9845 0.502412) (xy -2.9845 -0.513588)
			)
			(stroke
				(width 0)
				(type default)
			)
			(fill yes)
			(layer "F.SilkS")
		)
		(fp_poly
			(pts
				(xy -1.7145 -0.005588) (xy -2.9845 0.502412) (xy -2.9845 -0.513588)
			)
			(stroke
				(width 0)
				(type default)
			)
			(fill yes)
			(layer "B.SilkS")
		)
		(fp_poly
			(pts
				(xy -1.2827 -1.27) (xy -1.2827 13.97) (xy 3.8227 13.97) (xy 3.8227 -1.27)
			)
			(stroke
				(width 0)
				(type default)
			)
			(fill no)
			(layer "F.CrtYd")
		)
		(fp_poly
			(pts
				(xy -1.7145 -0.005588) (xy -2.9845 0.502412) (xy -2.9845 -0.513588)
			)
			(stroke
				(width 0)
				(type default)
			)
			(fill yes)
			(layer "B.Fab")
		)
		(fp_line
			(start 3.8227 -1.27)
			(end -1.2827 -1.27)
			(stroke
				(width 0.1)
				(type default)
			)
			(layer "F.Fab")
		)
		(fp_line
			(start -1.2827 -1.27)
			(end -1.2827 13.97)
			(stroke
				(width 0.1)
				(type default)
			)
			(layer "F.Fab")
		)
		(fp_line
			(start 3.8227 13.97)
			(end 3.8227 -1.27)
			(stroke
				(width 0.1)
				(type default)
			)
			(layer "F.Fab")
		)
		(fp_line
			(start -1.2827 13.97)
			(end 3.8227 13.97)
			(stroke
				(width 0.1)
				(type default)
			)
			(layer "F.Fab")
		)
		(fp_poly
			(pts
				(xy -1.7145 -0.005588) (xy -2.9845 0.502412) (xy -2.9845 -0.513588)
			)
			(stroke
				(width 0)
				(type default)
			)
			(fill yes)
			(layer "F.Fab")
		)
		(fp_text user "2"
			(at 4.41706 -0.0381 0)
			(unlocked yes)
			(layer "F.SilkS")
			(effects
				(font
					(size 0.7874 0.5842)
					(thickness 0.1524)
				)
			)
		)
		(fp_text user "12"
			(at 4.41325 13.23086 0)
			(unlocked yes)
			(layer "F.SilkS")
			(effects
				(font
					(size 0.7874 0.5842)
					(thickness 0.1524)
				)
			)
		)
		(fp_text user "11"
			(at 2.97561 14.7066 0)
			(unlocked yes)
			(layer "F.SilkS")
			(effects
				(font
					(size 0.7874 0.5842)
					(thickness 0.1524)
				)
			)
		)
		(fp_text user "12"
			(at -0.508 -1.47193 90)
			(unlocked yes)
			(layer "B.SilkS")
			(effects
				(font
					(size 0.7874 0.5842)
					(thickness 0.1524)
				)
				(justify mirror)
			)
		)
		(fp_text user "2"
			(at 4.01701 -0.93218 0)
			(unlocked yes)
			(layer "B.SilkS")
			(effects
				(font
					(size 0.7874 0.5842)
					(thickness 0.1524)
				)
				(justify mirror)
			)
		)
		(fp_text user "11"
			(at -1.40843 12.55268 0)
			(unlocked yes)
			(layer "B.SilkS")
			(effects
				(font
					(size 0.7874 0.5842)
					(thickness 0.1524)
				)
				(justify mirror)
			)
		)
		(fp_text user "2"
			(at 4.5466 0.02667 90)
			(unlocked yes)
			(layer "B.Fab")
			(effects
				(font
					(size 0.7874 0.5842)
					(thickness 0.1524)
				)
				(justify mirror)
			)
		)
		(fp_text user "12"
			(at 4.9403 12.72667 90)
			(unlocked yes)
			(layer "B.Fab")
			(effects
				(font
					(size 0.7874 0.5842)
					(thickness 0.1524)
				)
				(justify mirror)
			)
		)
		(fp_text user "11"
			(at -2.2606 12.72667 90)
			(unlocked yes)
			(layer "B.Fab")
			(effects
				(font
					(size 0.7874 0.5842)
					(thickness 0.1524)
				)
				(justify mirror)
			)
		)
		(fp_text user "2"
			(at 4.445 -0.980694 90)
			(unlocked yes)
			(layer "F.Fab")
			(effects
				(font
					(size 0.7874 0.5842)
					(thickness 0.1524)
				)
			)
		)
		(fp_text user "12"
			(at 4.826 10.703306 90)
			(unlocked yes)
			(layer "F.Fab")
			(effects
				(font
					(size 0.7874 0.5842)
					(thickness 0.1524)
				)
			)
		)
		(fp_text user "11"
			(at -1.4478 13.43787 90)
			(unlocked yes)
			(layer "F.Fab")
			(effects
				(font
					(size 0.7874 0.5842)
					(thickness 0.1524)
				)
			)
		)
		(pad "1" thru_hole rect
			(at 0 0 90)
			(size 1.6256 1.6256)
			(drill 1.2446)
			(layers "*.Cu" "*.Mask")
			(remove_unused_layers no)
			(net "TP_ME_RCVR_BOOT")
			(clearance 0.127)
			(thermal_gap 0.127)
			(padstack
				(mode front_inner_back)
				(layer "Inner"
					(shape circle)
					(size 1.6256 1.6256)
					(clearance 0.127)
				)
				(layer "B.Cu"
					(shape rect)
					(size 1.6256 1.6256)
					(clearance 0.127)
				)
			)
		)
		(pad "2" thru_hole circle
			(at 2.54 0 90)
			(size 1.6256 1.6256)
			(drill 1.2446)
			(layers "*.Cu" "*.Mask")
			(remove_unused_layers no)
			(net "TP_BIOS_USB_RECOVERY")
			(clearance 0.127)
			(thermal_gap 0.127)
		)
		(pad "3" thru_hole circle
			(at 0 2.54 90)
			(size 1.6256 1.6256)
			(drill 1.2446)
			(layers "*.Cu" "*.Mask")
			(remove_unused_layers no)
			(net "FM_ME_RECOVER_N")
			(clearance 0.127)
			(thermal_gap 0.127)
		)
		(pad "4" thru_hole circle
			(at 2.54 2.54 90)
			(size 1.6256 1.6256)
			(drill 1.2446)
			(layers "*.Cu" "*.Mask")
			(remove_unused_layers no)
			(net "FM_BIOS_USB_RECOVERY")
			(clearance 0.127)
			(thermal_gap 0.127)
		)
		(pad "5" thru_hole circle
			(at 0 5.08 90)
			(size 1.6256 1.6256)
			(drill 1.2446)
			(layers "*.Cu" "*.Mask")
			(remove_unused_layers no)
			(net "PD_ME_RCVR_N")
			(clearance 0.127)
			(thermal_gap 0.127)
		)
		(pad "6" thru_hole circle
			(at 2.54 5.08 90)
			(size 1.6256 1.6256)
			(drill 1.2446)
			(layers "*.Cu" "*.Mask")
			(remove_unused_layers no)
			(net "PU_BIOS_USB_RECOVERY")
			(clearance 0.127)
			(thermal_gap 0.127)
		)
		(pad "7" thru_hole circle
			(at 0 7.62 90)
			(size 1.6256 1.6256)
			(drill 1.2446)
			(layers "*.Cu" "*.Mask")
			(remove_unused_layers no)
			(net "TP_PASSWORD_CLEAR")
			(clearance 0.127)
			(thermal_gap 0.127)
		)
		(pad "8" thru_hole circle
			(at 2.54 7.62 90)
			(size 1.6256 1.6256)
			(drill 1.2446)
			(layers "*.Cu" "*.Mask")
			(remove_unused_layers no)
			(net "TP_BIOS_RECOVER_BOOT")
			(clearance 0.127)
			(thermal_gap 0.127)
		)
		(pad "9" thru_hole circle
			(at 0 10.16 90)
			(size 1.6256 1.6256)
			(drill 1.2446)
			(layers "*.Cu" "*.Mask")
			(remove_unused_layers no)
			(net "FM_PASSWORD_CLEAR_N")
			(clearance 0.127)
			(thermal_gap 0.127)
		)
		(pad "10" thru_hole circle
			(at 2.54 10.16 90)
			(size 1.6256 1.6256)
			(drill 1.2446)
			(layers "*.Cu" "*.Mask")
			(remove_unused_layers no)
			(net "FM_BIOS_TOP_SWAP")
			(clearance 0.127)
			(thermal_gap 0.127)
		)
		(pad "11" thru_hole circle
			(at 0 12.7 90)
			(size 1.6256 1.6256)
			(drill 1.2446)
			(layers "*.Cu" "*.Mask")
			(remove_unused_layers no)
			(net "PD_PASSWORD_CLEAR")
			(clearance 0.127)
			(thermal_gap 0.127)
		)
		(pad "12" thru_hole circle
			(at 2.54 12.7 90)
			(size 1.6256 1.6256)
			(drill 1.2446)
			(layers "*.Cu" "*.Mask")
			(remove_unused_layers no)
			(net "PU_BIOS_RECOVER_BOOT")
			(clearance 0.127)
			(thermal_gap 0.127)
		)
	)
	(footprint ""
		(layer "F.Cu")
		(at 338.836 -18.923 -90)
		(property "Reference" "R12W25"
			(at -0.8382 -0.67818 270)
			(unlocked yes)
			(layer "F.SilkS")
			(effects
				(font
					(size 0.4064 0.254)
					(thickness 0.1524)
				)
				(justify left)
			)
		)
		(property "Value" ""
			(at 0 0 270)
			(layer "F.Fab")
			(effects
				(font
					(size 1.27 1.27)
				)
			)
		)
		(duplicate_pad_numbers_are_jumpers no)
		(fp_poly
			(pts
				(xy -0.2794 -0.1016) (xy 0.2794 -0.1016) (xy 0.2794 0.9906) (xy -0.2794 0.9906)
			)
			(stroke
				(width 0)
				(type default)
			)
			(fill no)
			(layer "F.CrtYd")
		)
		(fp_line
			(start -0.2794 0.9906)
			(end 0.2794 0.9906)
			(stroke
				(width 0.1)
				(type default)
			)
			(layer "F.Fab")
		)
		(fp_line
			(start 0.2794 0.9906)
			(end 0.2794 -0.1016)
			(stroke
				(width 0.1)
				(type default)
			)
			(layer "F.Fab")
		)
		(fp_line
			(start -0.2794 -0.1016)
			(end -0.2794 0.9906)
			(stroke
				(width 0.1)
				(type default)
			)
			(layer "F.Fab")
		)
		(fp_line
			(start 0.2794 -0.1016)
			(end -0.2794 -0.1016)
			(stroke
				(width 0.1)
				(type default)
			)
			(layer "F.Fab")
		)
		(pad "1" smd rect
			(at 0 0 270)
			(size 0.508 0.508)
			(layers "F.Cu" "F.Mask" "F.Paste")
			(net "PU_VR_PVDDQ_ABC_FAULT1")
		)
		(pad "2" smd rect
			(at 0 0.889 270)
			(size 0.508 0.508)
			(layers "F.Cu" "F.Mask" "F.Paste")
			(net "PWRGD_PVDDQ_ABC")
		)
		(zone
			(layer "F.Cu")
			(hatch none 0.5)
			(connect_pads
				(clearance 0)
			)
			(min_thickness 0.25)
			(keepout
				(tracks not_allowed)
				(vias allowed)
				(pads allowed)
				(copperpour not_allowed)
				(footprints allowed)
			)
			(placement
				(enabled no)
				(sheetname "")
			)
			(fill
				(thermal_gap 0.5)
				(thermal_bridge_width 0.5)
				(island_removal_mode 0)
			)
			(polygon
				(pts
					(xy 338.201 -19.177) (xy 338.201 -18.669) (xy 338.582 -18.669) (xy 338.582 -19.177)
				)
			)
		)
		(zone
			(layer "F.Cu")
			(hatch none 0.5)
			(connect_pads
				(clearance 0)
			)
			(min_thickness 0.25)
			(keepout
				(tracks allowed)
				(vias not_allowed)
				(pads allowed)
				(copperpour not_allowed)
				(footprints allowed)
			)
			(placement
				(enabled no)
				(sheetname "")
			)
			(fill
				(thermal_gap 0.5)
				(thermal_bridge_width 0.5)
				(island_removal_mode 0)
			)
			(polygon
				(pts
					(xy 338.582 -19.177) (xy 338.582 -18.669) (xy 338.201 -18.669) (xy 338.201 -19.177)
				)
			)
		)
	)
)
